FILE_TYPE = CONNECTIVITY;
{Allegro Design Entry HDL 16.6-p007 (v16-6-112F) 10/10/2012}
"PAGE_NUMBER" = 261;
0"NC";
END.
